(kicad_pcb
	(version 20260206)
	(generator "pcbnew")
	(generator_version "10.0")
	(general
		(thickness 1.6)
		(legacy_teardrops no)
	)
	(paper "A4")
	(title_block
		(title "15969-1a.1015WZS0858.brd")
		(comment 1 "Tioga Pass / footprints 158-165 of 295")
	)
	(layers
		(0 "F.Cu" signal "TOP")
		(4 "In1.Cu" signal "L2GND")
		(6 "In2.Cu" signal "L3")
		(8 "In3.Cu" signal "L4")
		(10 "In4.Cu" signal "L5GND")
		(2 "B.Cu" signal "BOTTOM")
		(9 "F.Adhes" user "F.Adhesive")
		(11 "B.Adhes" user "B.Adhesive")
		(13 "F.Paste" user "Package Geometry/Pastemask Top")
		(15 "B.Paste" user "Package Geometry/Pastemask Bottom")
		(5 "F.SilkS" user "Ref Des/Silkscreen Top")
		(7 "B.SilkS" user "Ref Des/Silkscreen Bottom")
		(1 "F.Mask" user "Board Geometry/Soldermask Top")
		(3 "B.Mask" user "Board Geometry/Soldermask Bottom")
		(17 "Dwgs.User" user "User.Drawings")
		(19 "Cmts.User" user "User.Comments")
		(21 "Eco1.User" user "User.Eco1")
		(23 "Eco2.User" user "User.Eco2")
		(25 "Edge.Cuts" user "Board Geometry/Outline")
		(27 "Margin" user)
		(31 "F.CrtYd" user "Package Geometry/Place Bound Top")
		(29 "B.CrtYd" user "Package Geometry/Place Bound Bottom")
		(35 "F.Fab" user "Ref Des/Assembly Top")
		(33 "B.Fab" user "Ref Des/Assembly Bottom")
	)
	(footprint ""
		(layer "F.Cu")
		(at 108.1532 0.2794)
		(property "Reference" "R13"
			(at 0 0 0)
			(layer "F.SilkS")
			(hide yes)
			(effects
				(font
					(size 1.27 1.27)
				)
			)
		)
		(property "Value" "10KR2F-2-GP"
			(at 0.064008 -3.993896 0)
			(unlocked yes)
			(layer "F.Fab")
			(hide yes)
			(effects
				(font
					(size 1.016 1.016)
					(thickness 0.1524)
				)
			)
		)
		(property "Device Type" "R402H16"
			(at 0.064008 -5.517896 0)
			(unlocked yes)
			(layer "F.Fab")
			(hide yes)
			(effects
				(font
					(size 1.016 1.016)
					(thickness 0.1524)
				)
			)
		)
		(duplicate_pad_numbers_are_jumpers no)
		(fp_line
			(start -0.508 -0.9398)
			(end -0.508 0.9398)
			(stroke
				(width 0.1524)
				(type default)
			)
			(layer "F.SilkS")
		)
		(fp_line
			(start 0.508 -0.9398)
			(end -0.508 -0.9398)
			(stroke
				(width 0.1524)
				(type default)
			)
			(layer "F.SilkS")
		)
		(fp_rect
			(start -0.508 0.9398)
			(end 0.508 -0.9398)
			(stroke
				(width 0)
				(type default)
			)
			(fill no)
			(layer "F.CrtYd")
		)
		(fp_rect
			(start -0.508 0.9398)
			(end 0.508 -0.9398)
			(stroke
				(width 0)
				(type default)
			)
			(fill no)
			(layer "F.Fab")
		)
		(pad "1" smd custom
			(at 0 -0.4445)
			(size 0.1397 0.1397)
			(layers "F.Cu" "F.Mask" "F.Paste")
			(net "P3V3_STBY")
			(options
				(clearance outline)
				(anchor circle)
			)
			(primitives
				(gr_poly
					(pts
						(arc
							(start -0.1778 -0.2794)
							(mid -0.249642 -0.249642)
							(end -0.2794 -0.1778)
						)
						(arc
							(start -0.2794 0.1778)
							(mid -0.249642 0.249642)
							(end -0.1778 0.2794)
						)
						(arc
							(start 0.1778 0.2794)
							(mid 0.249642 0.249642)
							(end 0.2794 0.1778)
						)
						(arc
							(start 0.2794 -0.1778)
							(mid 0.249642 -0.249642)
							(end 0.1778 -0.2794)
						)
					)
					(width 0)
					(fill yes)
				)
			)
		)
		(pad "2" smd custom
			(at 0 0.4445)
			(size 0.1397 0.1397)
			(layers "F.Cu" "F.Mask" "F.Paste")
			(net "SMB_B_HUB_A1")
			(options
				(clearance outline)
				(anchor circle)
			)
			(primitives
				(gr_poly
					(pts
						(arc
							(start -0.1778 -0.2794)
							(mid -0.249642 -0.249642)
							(end -0.2794 -0.1778)
						)
						(arc
							(start -0.2794 0.1778)
							(mid -0.249642 0.249642)
							(end -0.1778 0.2794)
						)
						(arc
							(start 0.1778 0.2794)
							(mid 0.249642 0.249642)
							(end 0.2794 0.1778)
						)
						(arc
							(start 0.2794 -0.1778)
							(mid 0.249642 -0.249642)
							(end 0.1778 -0.2794)
						)
					)
					(width 0)
					(fill yes)
				)
			)
		)
	)
	(footprint ""
		(layer "F.Cu")
		(at 22.86 -22.3012 -90)
		(property "Reference" "C48"
			(at 0 0 270)
			(layer "F.SilkS")
			(hide yes)
			(effects
				(font
					(size 1.27 1.27)
				)
			)
		)
		(property "Value" "SCD1U16V2KX-3GP"
			(at 1.1811 -2.7051 270)
			(unlocked yes)
			(layer "F.Fab")
			(hide yes)
			(effects
				(font
					(size 1.016 1.016)
					(thickness 0.1524)
				)
			)
		)
		(property "Device Type" "C402H22"
			(at 1.1811 -4.2291 270)
			(unlocked yes)
			(layer "F.Fab")
			(hide yes)
			(effects
				(font
					(size 1.016 1.016)
					(thickness 0.1524)
				)
			)
		)
		(duplicate_pad_numbers_are_jumpers no)
		(fp_rect
			(start -0.4318 0.9525)
			(end 0.4318 -0.9525)
			(stroke
				(width 0)
				(type default)
			)
			(fill no)
			(layer "F.CrtYd")
		)
		(fp_rect
			(start -0.4318 0.9525)
			(end 0.4318 -0.9525)
			(stroke
				(width 0)
				(type default)
			)
			(fill no)
			(layer "F.Fab")
		)
		(pad "1" smd custom
			(at 0 -0.4445 270)
			(size 0.1524 0.1524)
			(layers "F.Cu" "F.Mask" "F.Paste")
			(net "P3V3_STBY")
			(options
				(clearance outline)
				(anchor circle)
			)
			(primitives
				(gr_poly
					(pts
						(arc
							(start 0.3048 -0.2032)
							(mid 0.275042 -0.275042)
							(end 0.2032 -0.3048)
						)
						(arc
							(start -0.2032 -0.3048)
							(mid -0.275042 -0.275042)
							(end -0.3048 -0.2032)
						)
						(arc
							(start -0.3048 0.2032)
							(mid -0.275042 0.275042)
							(end -0.2032 0.3048)
						)
						(arc
							(start 0.2032 0.3048)
							(mid 0.275042 0.275042)
							(end 0.3048 0.2032)
						)
					)
					(width 0)
					(fill yes)
				)
			)
		)
		(pad "2" smd custom
			(at 0 0.4445 270)
			(size 0.1524 0.1524)
			(layers "F.Cu" "F.Mask" "F.Paste")
			(net "GND")
			(options
				(clearance outline)
				(anchor circle)
			)
			(primitives
				(gr_poly
					(pts
						(arc
							(start 0.3048 -0.2032)
							(mid 0.275042 -0.275042)
							(end 0.2032 -0.3048)
						)
						(arc
							(start -0.2032 -0.3048)
							(mid -0.275042 -0.275042)
							(end -0.3048 -0.2032)
						)
						(arc
							(start -0.3048 0.2032)
							(mid -0.275042 0.275042)
							(end -0.2032 0.3048)
						)
						(arc
							(start 0.2032 0.3048)
							(mid 0.275042 0.275042)
							(end 0.3048 0.2032)
						)
					)
					(width 0)
					(fill yes)
				)
			)
		)
	)
	(footprint ""
		(layer "F.Cu")
		(at 25.6921 4.1656 -90)
		(property "Reference" "R1"
			(at 0 0 270)
			(layer "F.SilkS")
			(hide yes)
			(effects
				(font
					(size 1.27 1.27)
				)
			)
		)
		(property "Value" "475R2F-L1-GP"
			(at 0.064008 -3.993896 270)
			(unlocked yes)
			(layer "F.Fab")
			(hide yes)
			(effects
				(font
					(size 1.016 1.016)
					(thickness 0.1524)
				)
			)
		)
		(property "Device Type" "R402H16"
			(at 0.064008 -5.517896 270)
			(unlocked yes)
			(layer "F.Fab")
			(hide yes)
			(effects
				(font
					(size 1.016 1.016)
					(thickness 0.1524)
				)
			)
		)
		(duplicate_pad_numbers_are_jumpers no)
		(fp_line
			(start -0.508 -0.9398)
			(end -0.508 0.9398)
			(stroke
				(width 0.1524)
				(type default)
			)
			(layer "F.SilkS")
		)
		(fp_line
			(start 0.508 -0.9398)
			(end -0.508 -0.9398)
			(stroke
				(width 0.1524)
				(type default)
			)
			(layer "F.SilkS")
		)
		(fp_rect
			(start -0.508 0.9398)
			(end 0.508 -0.9398)
			(stroke
				(width 0)
				(type default)
			)
			(fill no)
			(layer "F.CrtYd")
		)
		(fp_rect
			(start -0.508 0.9398)
			(end 0.508 -0.9398)
			(stroke
				(width 0)
				(type default)
			)
			(fill no)
			(layer "F.Fab")
		)
		(pad "1" smd custom
			(at 0 -0.4445 270)
			(size 0.1397 0.1397)
			(layers "F.Cu" "F.Mask" "F.Paste")
			(net "GND")
			(options
				(clearance outline)
				(anchor circle)
			)
			(primitives
				(gr_poly
					(pts
						(arc
							(start -0.1778 -0.2794)
							(mid -0.249642 -0.249642)
							(end -0.2794 -0.1778)
						)
						(arc
							(start -0.2794 0.1778)
							(mid -0.249642 0.249642)
							(end -0.1778 0.2794)
						)
						(arc
							(start 0.1778 0.2794)
							(mid 0.249642 0.249642)
							(end 0.2794 0.1778)
						)
						(arc
							(start 0.2794 -0.1778)
							(mid 0.249642 -0.249642)
							(end 0.1778 -0.2794)
						)
					)
					(width 0)
					(fill yes)
				)
			)
		)
		(pad "2" smd custom
			(at 0 0.4445 270)
			(size 0.1397 0.1397)
			(layers "F.Cu" "F.Mask" "F.Paste")
			(net "FM_SLT_CFG0")
			(options
				(clearance outline)
				(anchor circle)
			)
			(primitives
				(gr_poly
					(pts
						(arc
							(start -0.1778 -0.2794)
							(mid -0.249642 -0.249642)
							(end -0.2794 -0.1778)
						)
						(arc
							(start -0.2794 0.1778)
							(mid -0.249642 0.249642)
							(end -0.1778 0.2794)
						)
						(arc
							(start 0.1778 0.2794)
							(mid 0.249642 0.249642)
							(end 0.2794 0.1778)
						)
						(arc
							(start 0.2794 -0.1778)
							(mid 0.249642 -0.249642)
							(end 0.1778 -0.2794)
						)
					)
					(width 0)
					(fill yes)
				)
			)
		)
	)
	(footprint ""
		(layer "F.Cu")
		(at 129.286 -29.3624 90)
		(property "Reference" "CU10"
			(at 0 0 90)
			(layer "F.SilkS")
			(hide yes)
			(effects
				(font
					(size 1.27 1.27)
				)
			)
		)
		(property "Value" "SC1U10V2KX-4-GP"
			(at 1.1811 -2.7051 90)
			(unlocked yes)
			(layer "F.Fab")
			(hide yes)
			(effects
				(font
					(size 1.016 1.016)
					(thickness 0.1524)
				)
			)
		)
		(property "Device Type" "C402H22"
			(at 1.1811 -4.2291 90)
			(unlocked yes)
			(layer "F.Fab")
			(hide yes)
			(effects
				(font
					(size 1.016 1.016)
					(thickness 0.1524)
				)
			)
		)
		(duplicate_pad_numbers_are_jumpers no)
		(fp_rect
			(start -0.4318 0.9525)
			(end 0.4318 -0.9525)
			(stroke
				(width 0)
				(type default)
			)
			(fill no)
			(layer "F.CrtYd")
		)
		(fp_rect
			(start -0.4318 0.9525)
			(end 0.4318 -0.9525)
			(stroke
				(width 0)
				(type default)
			)
			(fill no)
			(layer "F.Fab")
		)
		(pad "1" smd custom
			(at 0 -0.4445 90)
			(size 0.1524 0.1524)
			(layers "F.Cu" "F.Mask" "F.Paste")
			(net "PLLFILT")
			(options
				(clearance outline)
				(anchor circle)
			)
			(primitives
				(gr_poly
					(pts
						(arc
							(start 0.3048 -0.2032)
							(mid 0.275042 -0.275042)
							(end 0.2032 -0.3048)
						)
						(arc
							(start -0.2032 -0.3048)
							(mid -0.275042 -0.275042)
							(end -0.3048 -0.2032)
						)
						(arc
							(start -0.3048 0.2032)
							(mid -0.275042 0.275042)
							(end -0.2032 0.3048)
						)
						(arc
							(start 0.2032 0.3048)
							(mid 0.275042 0.275042)
							(end 0.3048 0.2032)
						)
					)
					(width 0)
					(fill yes)
				)
			)
		)
		(pad "2" smd custom
			(at 0 0.4445 90)
			(size 0.1524 0.1524)
			(layers "F.Cu" "F.Mask" "F.Paste")
			(net "GND")
			(options
				(clearance outline)
				(anchor circle)
			)
			(primitives
				(gr_poly
					(pts
						(arc
							(start 0.3048 -0.2032)
							(mid 0.275042 -0.275042)
							(end 0.2032 -0.3048)
						)
						(arc
							(start -0.2032 -0.3048)
							(mid -0.275042 -0.275042)
							(end -0.3048 -0.2032)
						)
						(arc
							(start -0.3048 0.2032)
							(mid -0.275042 0.275042)
							(end -0.2032 0.3048)
						)
						(arc
							(start 0.2032 0.3048)
							(mid 0.275042 0.275042)
							(end 0.3048 0.2032)
						)
					)
					(width 0)
					(fill yes)
				)
			)
		)
	)
	(footprint ""
		(layer "F.Cu")
		(at 38.6588 -3.7719 90)
		(property "Reference" "C796"
			(at 0 0 90)
			(layer "F.SilkS")
			(hide yes)
			(effects
				(font
					(size 1.27 1.27)
				)
			)
		)
		(property "Value" "SC22U6D3V5MX-5-GP"
			(at -0.0762 -6.1214 90)
			(unlocked yes)
			(layer "F.Fab")
			(hide yes)
			(effects
				(font
					(size 1.016 1.016)
					(thickness 0.1524)
				)
			)
		)
		(property "Device Type" "C805H56"
			(at -0.0762 -8.1534 90)
			(unlocked yes)
			(layer "F.Fab")
			(hide yes)
			(effects
				(font
					(size 1.016 1.016)
					(thickness 0.1524)
				)
			)
		)
		(duplicate_pad_numbers_are_jumpers no)
		(fp_line
			(start 0.635 0)
			(end -0.635 0)
			(stroke
				(width 0.508)
				(type default)
			)
			(layer "F.SilkS")
		)
		(fp_rect
			(start -0.9652 1.778)
			(end 0.9652 -1.778)
			(stroke
				(width 0)
				(type default)
			)
			(fill no)
			(layer "F.CrtYd")
		)
		(fp_poly
			(pts
				(xy -0.9652 -1.778) (xy 0.9652 -1.778) (xy 0.9652 1.778) (xy -0.9652 1.778)
			)
			(stroke
				(width 0)
				(type default)
			)
			(fill no)
			(layer "F.Fab")
		)
		(pad "1" smd rect
			(at 0 -0.9652 90)
			(size 1.397 1.143)
			(layers "F.Cu" "F.Mask" "F.Paste")
			(net "P3V3")
		)
		(pad "2" smd rect
			(at 0 0.9652 90)
			(size 1.397 1.143)
			(layers "F.Cu" "F.Mask" "F.Paste")
			(net "GND")
		)
	)
	(footprint ""
		(layer "F.Cu")
		(at 132.207 -6.7564 -90)
		(property "Reference" "R147"
			(at 0 0 270)
			(layer "F.SilkS")
			(hide yes)
			(effects
				(font
					(size 1.27 1.27)
				)
			)
		)
		(property "Value" "10KR2F-2-GP"
			(at 0.064008 -3.993896 270)
			(unlocked yes)
			(layer "F.Fab")
			(hide yes)
			(effects
				(font
					(size 1.016 1.016)
					(thickness 0.1524)
				)
			)
		)
		(property "Device Type" "R402H16"
			(at 0.064008 -5.517896 270)
			(unlocked yes)
			(layer "F.Fab")
			(hide yes)
			(effects
				(font
					(size 1.016 1.016)
					(thickness 0.1524)
				)
			)
		)
		(duplicate_pad_numbers_are_jumpers no)
		(fp_line
			(start -0.508 -0.9398)
			(end -0.508 0.9398)
			(stroke
				(width 0.1524)
				(type default)
			)
			(layer "F.SilkS")
		)
		(fp_line
			(start 0.508 -0.9398)
			(end -0.508 -0.9398)
			(stroke
				(width 0.1524)
				(type default)
			)
			(layer "F.SilkS")
		)
		(fp_rect
			(start -0.508 0.9398)
			(end 0.508 -0.9398)
			(stroke
				(width 0)
				(type default)
			)
			(fill no)
			(layer "F.CrtYd")
		)
		(fp_rect
			(start -0.508 0.9398)
			(end 0.508 -0.9398)
			(stroke
				(width 0)
				(type default)
			)
			(fill no)
			(layer "F.Fab")
		)
		(pad "1" smd custom
			(at 0 -0.4445 270)
			(size 0.1397 0.1397)
			(layers "F.Cu" "F.Mask" "F.Paste")
			(net "P3V3_STBY")
			(options
				(clearance outline)
				(anchor circle)
			)
			(primitives
				(gr_poly
					(pts
						(arc
							(start -0.1778 -0.2794)
							(mid -0.249642 -0.249642)
							(end -0.2794 -0.1778)
						)
						(arc
							(start -0.2794 0.1778)
							(mid -0.249642 0.249642)
							(end -0.1778 0.2794)
						)
						(arc
							(start 0.1778 0.2794)
							(mid 0.249642 0.249642)
							(end 0.2794 0.1778)
						)
						(arc
							(start 0.2794 -0.1778)
							(mid 0.249642 -0.249642)
							(end 0.1778 -0.2794)
						)
					)
					(width 0)
					(fill yes)
				)
			)
		)
		(pad "2" smd custom
			(at 0 0.4445 270)
			(size 0.1397 0.1397)
			(layers "F.Cu" "F.Mask" "F.Paste")
			(net "GPIO_P_EXP_A1")
			(options
				(clearance outline)
				(anchor circle)
			)
			(primitives
				(gr_poly
					(pts
						(arc
							(start -0.1778 -0.2794)
							(mid -0.249642 -0.249642)
							(end -0.2794 -0.1778)
						)
						(arc
							(start -0.2794 0.1778)
							(mid -0.249642 0.249642)
							(end -0.1778 0.2794)
						)
						(arc
							(start 0.1778 0.2794)
							(mid 0.249642 0.249642)
							(end 0.2794 0.1778)
						)
						(arc
							(start 0.2794 -0.1778)
							(mid 0.249642 -0.249642)
							(end 0.1778 -0.2794)
						)
					)
					(width 0)
					(fill yes)
				)
			)
		)
	)
	(footprint ""
		(layer "F.Cu")
		(at 31.9659 0.6477 90)
		(property "Reference" "R204"
			(at 0 0 90)
			(layer "F.SilkS")
			(hide yes)
			(effects
				(font
					(size 1.27 1.27)
				)
			)
		)
		(property "Value" "0R6J-3-GP"
			(at -0.0508 -4.8514 90)
			(unlocked yes)
			(layer "F.Fab")
			(hide yes)
			(effects
				(font
					(size 1.016 1.016)
					(thickness 0.1524)
				)
			)
		)
		(property "Device Type" "R1206H28"
			(at 0 -6.3754 90)
			(unlocked yes)
			(layer "F.Fab")
			(hide yes)
			(effects
				(font
					(size 1.016 1.016)
					(thickness 0.1524)
				)
			)
		)
		(duplicate_pad_numbers_are_jumpers no)
		(fp_line
			(start 1.016 -2.2352)
			(end 1.016 2.2352)
			(stroke
				(width 0.1524)
				(type default)
			)
			(layer "F.SilkS")
		)
		(fp_line
			(start -1.016 -2.2352)
			(end 1.016 -2.2352)
			(stroke
				(width 0.1524)
				(type default)
			)
			(layer "F.SilkS")
		)
		(fp_line
			(start 1.016 2.2352)
			(end -1.016 2.2352)
			(stroke
				(width 0.1524)
				(type default)
			)
			(layer "F.SilkS")
		)
		(fp_line
			(start -1.016 2.2352)
			(end -1.016 -2.2352)
			(stroke
				(width 0.1524)
				(type default)
			)
			(layer "F.SilkS")
		)
		(fp_rect
			(start -1.0922 2.3114)
			(end 1.0922 -2.3114)
			(stroke
				(width 0)
				(type default)
			)
			(fill no)
			(layer "F.CrtYd")
		)
		(fp_poly
			(pts
				(xy -1.0922 -2.3114) (xy 1.0922 -2.3114) (xy 1.0922 2.3114) (xy -1.0922 2.3114)
			)
			(stroke
				(width 0)
				(type default)
			)
			(fill no)
			(layer "F.Fab")
		)
		(pad "1" smd rect
			(at 0 -1.397 90)
			(size 1.651 1.27)
			(layers "F.Cu" "F.Mask" "F.Paste")
			(net "P3V3_VR")
		)
		(pad "2" smd rect
			(at 0 1.397 90)
			(size 1.651 1.27)
			(layers "F.Cu" "F.Mask" "F.Paste")
			(net "P3V3")
		)
	)
	(footprint ""
		(layer "F.Cu")
		(at 119.1768 -14.5542 90)
		(property "Reference" "R42"
			(at 0 0 90)
			(layer "F.SilkS")
			(hide yes)
			(effects
				(font
					(size 1.27 1.27)
				)
			)
		)
		(property "Value" "4K7R2F-GP"
			(at 0.064008 -3.993896 90)
			(unlocked yes)
			(layer "F.Fab")
			(hide yes)
			(effects
				(font
					(size 1.016 1.016)
					(thickness 0.1524)
				)
			)
		)
		(property "Device Type" "R402H16"
			(at 0.064008 -5.517896 90)
			(unlocked yes)
			(layer "F.Fab")
			(hide yes)
			(effects
				(font
					(size 1.016 1.016)
					(thickness 0.1524)
				)
			)
		)
		(duplicate_pad_numbers_are_jumpers no)
		(fp_line
			(start 0.508 -0.9398)
			(end -0.508 -0.9398)
			(stroke
				(width 0.1524)
				(type default)
			)
			(layer "F.SilkS")
		)
		(fp_line
			(start -0.508 -0.9398)
			(end -0.508 0.9398)
			(stroke
				(width 0.1524)
				(type default)
			)
			(layer "F.SilkS")
		)
		(fp_rect
			(start -0.508 0.9398)
			(end 0.508 -0.9398)
			(stroke
				(width 0)
				(type default)
			)
			(fill no)
			(layer "F.CrtYd")
		)
		(fp_rect
			(start -0.508 0.9398)
			(end 0.508 -0.9398)
			(stroke
				(width 0)
				(type default)
			)
			(fill no)
			(layer "F.Fab")
		)
		(pad "1" smd custom
			(at 0 -0.4445 90)
			(size 0.1397 0.1397)
			(layers "F.Cu" "F.Mask" "F.Paste")
			(net "P3V3_STBY")
			(options
				(clearance outline)
				(anchor circle)
			)
			(primitives
				(gr_poly
					(pts
						(arc
							(start -0.1778 -0.2794)
							(mid -0.249642 -0.249642)
							(end -0.2794 -0.1778)
						)
						(arc
							(start -0.2794 0.1778)
							(mid -0.249642 0.249642)
							(end -0.1778 0.2794)
						)
						(arc
							(start 0.1778 0.2794)
							(mid 0.249642 0.249642)
							(end 0.2794 0.1778)
						)
						(arc
							(start 0.2794 -0.1778)
							(mid 0.249642 -0.249642)
							(end 0.1778 -0.2794)
						)
					)
					(width 0)
					(fill yes)
				)
			)
		)
		(pad "2" smd custom
			(at 0 0.4445 90)
			(size 0.1397 0.1397)
			(layers "F.Cu" "F.Mask" "F.Paste")
			(net "PCIE_SLOT3_PRSNT2_1_N")
			(options
				(clearance outline)
				(anchor circle)
			)
			(primitives
				(gr_poly
					(pts
						(arc
							(start -0.1778 -0.2794)
							(mid -0.249642 -0.249642)
							(end -0.2794 -0.1778)
						)
						(arc
							(start -0.2794 0.1778)
							(mid -0.249642 0.249642)
							(end -0.1778 0.2794)
						)
						(arc
							(start 0.1778 0.2794)
							(mid 0.249642 0.249642)
							(end 0.2794 0.1778)
						)
						(arc
							(start 0.2794 -0.1778)
							(mid 0.249642 -0.249642)
							(end 0.1778 -0.2794)
						)
					)
					(width 0)
					(fill yes)
				)
			)
		)
	)
)
